# SCM (Grand Teton) — schematic netlist excerpt (pin names and nets, part order shuffled) for the footprints in the layout excerpt that follows; sources: Cadence DE-HDL packaged netlist, KiCad conversion of 12092022_DA0F0TMDCD0_F0T_Management_Board_D_brd_V3_OCP.brd

Q7  2N7002A7  2N7002A-7 IC  pkg SOT23_GDSXC  page 27
  D  = Q7_D
  G  = LPC_ESPI_SEL_R1
  S  = SPI_BMC_TPM_MOSI

C139  Q_CAP  0.1UF 25V 10% X7R  pkg 0402  page 17 : A = P1V2_P1V0_I3C_VDDL1 ; B = GND

(kicad_pcb
	(version 20260206)
	(generator "pcbnew")
	(generator_version "10.0")
	(general
		(thickness 1.6)
		(legacy_teardrops no)
	)
	(paper "A4")
	(title_block
		(title "12092022_DA0F0TMDCD0_F0T_Management_Board_D_brd_V3_OCP.brd")
		(comment 1 "Grand Teton / footprints 731-732 of 1440")
	)
	(layers
		(0 "F.Cu" signal "TOP")
		(4 "In1.Cu" signal "GND")
		(6 "In2.Cu" signal "IN1")
		(8 "In3.Cu" signal "GND1")
		(10 "In4.Cu" signal "IN2")
		(12 "In5.Cu" signal "VCC")
		(14 "In6.Cu" signal "VCC1")
		(16 "In7.Cu" signal "IN3")
		(18 "In8.Cu" signal "GND2")
		(20 "In9.Cu" signal "IN4")
		(22 "In10.Cu" signal "GND3")
		(2 "B.Cu" signal "BOTTOM")
		(9 "F.Adhes" user "F.Adhesive")
		(11 "B.Adhes" user "B.Adhesive")
		(13 "F.Paste" user "Package Geometry/Pastemask Top")
		(15 "B.Paste" user "Package Geometry/Pastemask Bottom")
		(5 "F.SilkS" user "Ref Des/Silkscreen Top")
		(7 "B.SilkS" user "Ref Des/Silkscreen Bottom")
		(1 "F.Mask" user "Board Geometry/Soldermask Top")
		(3 "B.Mask" user "Board Geometry/Soldermask Bottom")
		(17 "Dwgs.User" user "User.Drawings")
		(19 "Cmts.User" user "User.Comments")
		(21 "Eco1.User" user "User.Eco1")
		(23 "Eco2.User" user "User.Eco2")
		(25 "Edge.Cuts" user "Board Geometry/Outline")
		(27 "Margin" user)
		(31 "F.CrtYd" user "Package Geometry/Place Bound Top")
		(29 "B.CrtYd" user "Package Geometry/Place Bound Bottom")
		(35 "F.Fab" user "Ref Des/Assembly Top")
		(33 "B.Fab" user "Ref Des/Assembly Bottom")
	)
	(footprint ""
		(layer "B.Cu")
		(at 74.715878 -96.50984 90)
		(property "Reference" "Q7"
			(at 2.24409 0.315722 0)
			(unlocked yes)
			(layer "B.SilkS")
			(effects
				(font
					(size 0.7874 0.5842)
					(thickness 0.1524)
				)
				(justify left mirror)
			)
		)
		(property "Value" ""
			(at 0 0 90)
			(layer "B.Fab")
			(effects
				(font
					(size 1.27 1.27)
				)
				(justify mirror)
			)
		)
		(duplicate_pad_numbers_are_jumpers no)
		(fp_line
			(start 1.603248 -1.500124)
			(end -1.603248 -1.500124)
			(stroke
				(width 0.1524)
				(type default)
			)
			(layer "B.SilkS")
		)
		(fp_line
			(start -1.603248 -1.500124)
			(end -1.603248 1.500124)
			(stroke
				(width 0.1524)
				(type default)
			)
			(layer "B.SilkS")
		)
		(fp_line
			(start 1.603248 1.500124)
			(end 1.603248 -1.500124)
			(stroke
				(width 0.1524)
				(type default)
			)
			(layer "B.SilkS")
		)
		(fp_line
			(start -1.603248 1.500124)
			(end 1.603248 1.500124)
			(stroke
				(width 0.1524)
				(type default)
			)
			(layer "B.SilkS")
		)
		(fp_line
			(start 0.700024 -1.500124)
			(end 0.700024 -1.169924)
			(stroke
				(width 0.1)
				(type default)
			)
			(layer "B.Fab")
		)
		(fp_line
			(start -0.700024 -1.500124)
			(end 0.700024 -1.500124)
			(stroke
				(width 0.1)
				(type default)
			)
			(layer "B.Fab")
		)
		(fp_line
			(start 1.249934 -1.169924)
			(end 1.249934 -0.729996)
			(stroke
				(width 0.1)
				(type default)
			)
			(layer "B.Fab")
		)
		(fp_line
			(start 0.700024 -1.169924)
			(end 1.249934 -1.169924)
			(stroke
				(width 0.1)
				(type default)
			)
			(layer "B.Fab")
		)
		(fp_line
			(start 1.249934 -0.729996)
			(end 0.6985 -0.729996)
			(stroke
				(width 0.1)
				(type default)
			)
			(layer "B.Fab")
		)
		(fp_line
			(start 0.6985 -0.729996)
			(end 0.6985 0.729996)
			(stroke
				(width 0.1)
				(type default)
			)
			(layer "B.Fab")
		)
		(fp_line
			(start -0.700024 -0.219964)
			(end -0.700024 -1.500124)
			(stroke
				(width 0.1)
				(type default)
			)
			(layer "B.Fab")
		)
		(fp_line
			(start -1.249934 -0.219964)
			(end -0.700024 -0.219964)
			(stroke
				(width 0.1)
				(type default)
			)
			(layer "B.Fab")
		)
		(fp_line
			(start -0.700024 0.219964)
			(end -1.249934 0.219964)
			(stroke
				(width 0.1)
				(type default)
			)
			(layer "B.Fab")
		)
		(fp_line
			(start -1.249934 0.219964)
			(end -1.249934 -0.219964)
			(stroke
				(width 0.1)
				(type default)
			)
			(layer "B.Fab")
		)
		(fp_line
			(start 1.249934 0.729996)
			(end 1.249934 1.169924)
			(stroke
				(width 0.1)
				(type default)
			)
			(layer "B.Fab")
		)
		(fp_line
			(start 0.6985 0.729996)
			(end 1.249934 0.729996)
			(stroke
				(width 0.1)
				(type default)
			)
			(layer "B.Fab")
		)
		(fp_line
			(start 1.249934 1.169924)
			(end 0.700024 1.169924)
			(stroke
				(width 0.1)
				(type default)
			)
			(layer "B.Fab")
		)
		(fp_line
			(start 0.700024 1.169924)
			(end 0.700024 1.500124)
			(stroke
				(width 0.1)
				(type default)
			)
			(layer "B.Fab")
		)
		(fp_line
			(start 0.700024 1.500124)
			(end -0.700024 1.500124)
			(stroke
				(width 0.1)
				(type default)
			)
			(layer "B.Fab")
		)
		(fp_line
			(start -0.700024 1.500124)
			(end -0.700024 0.219964)
			(stroke
				(width 0.1)
				(type default)
			)
			(layer "B.Fab")
		)
		(fp_rect
			(start 0.700024 1.500124)
			(end -0.700024 -1.500124)
			(stroke
				(width 0)
				(type default)
			)
			(fill no)
			(layer "B.Fab")
		)
		(pad "D" smd rect
			(at -0.999998 0)
			(size 0.8128 0.9144)
			(layers "B.Cu" "B.Mask" "B.Paste")
			(net "Q7_D")
		)
		(pad "G" smd rect
			(at 0.999998 -0.94996)
			(size 0.8128 0.9144)
			(layers "B.Cu" "B.Mask" "B.Paste")
			(net "LPC_ESPI_SEL_R1")
		)
		(pad "S" smd rect
			(at 0.999998 0.94996)
			(size 0.8128 0.9144)
			(layers "B.Cu" "B.Mask" "B.Paste")
			(net "SPI_BMC_TPM_MOSI")
		)
	)
	(footprint ""
		(layer "B.Cu")
		(at 49.5046 -53.2638 180)
		(property "Reference" "C139"
			(at 0 0 0)
			(layer "B.SilkS")
			(hide yes)
			(effects
				(font
					(size 1.27 1.27)
				)
				(justify mirror)
			)
		)
		(property "Value" ""
			(at 0 0 0)
			(layer "B.Fab")
			(effects
				(font
					(size 1.27 1.27)
				)
				(justify mirror)
			)
		)
		(duplicate_pad_numbers_are_jumpers no)
		(fp_line
			(start 0.7874 0.4064)
			(end 0.7874 -0.4064)
			(stroke
				(width 0.1524)
				(type default)
			)
			(layer "B.SilkS")
		)
		(fp_line
			(start 0.7874 -0.4064)
			(end -0.7874 -0.4064)
			(stroke
				(width 0.1524)
				(type default)
			)
			(layer "B.SilkS")
		)
		(fp_line
			(start -0.7874 0.4064)
			(end 0.7874 0.4064)
			(stroke
				(width 0.1524)
				(type default)
			)
			(layer "B.SilkS")
		)
		(fp_line
			(start -0.7874 -0.4064)
			(end -0.7874 0.4064)
			(stroke
				(width 0.1524)
				(type default)
			)
			(layer "B.SilkS")
		)
		(fp_line
			(start 0.67945 0.3048)
			(end 0.67945 -0.305054)
			(stroke
				(width 0.1)
				(type default)
			)
			(layer "B.Fab")
		)
		(fp_line
			(start 0.67945 -0.305054)
			(end 0.12065 -0.305054)
			(stroke
				(width 0.1)
				(type default)
			)
			(layer "B.Fab")
		)
		(fp_line
			(start 0.12065 0.3048)
			(end 0.67945 0.3048)
			(stroke
				(width 0.1)
				(type default)
			)
			(layer "B.Fab")
		)
		(fp_line
			(start 0.12065 0.2794)
			(end 0.12065 0.3048)
			(stroke
				(width 0.1)
				(type default)
			)
			(layer "B.Fab")
		)
		(fp_line
			(start 0.12065 -0.2794)
			(end -0.12065 -0.2794)
			(stroke
				(width 0.1)
				(type default)
			)
			(layer "B.Fab")
		)
		(fp_line
			(start 0.12065 -0.305054)
			(end 0.12065 -0.2794)
			(stroke
				(width 0.1)
				(type default)
			)
			(layer "B.Fab")
		)
		(fp_line
			(start -0.120396 0.3048)
			(end -0.120396 0.2794)
			(stroke
				(width 0.1)
				(type default)
			)
			(layer "B.Fab")
		)
		(fp_line
			(start -0.120396 0.2794)
			(end 0.12065 0.2794)
			(stroke
				(width 0.1)
				(type default)
			)
			(layer "B.Fab")
		)
		(fp_line
			(start -0.12065 -0.2794)
			(end -0.12065 -0.3048)
			(stroke
				(width 0.1)
				(type default)
			)
			(layer "B.Fab")
		)
		(fp_line
			(start -0.12065 -0.3048)
			(end -0.67945 -0.3048)
			(stroke
				(width 0.1)
				(type default)
			)
			(layer "B.Fab")
		)
		(fp_line
			(start -0.67945 0.3048)
			(end -0.120396 0.3048)
			(stroke
				(width 0.1)
				(type default)
			)
			(layer "B.Fab")
		)
		(fp_line
			(start -0.67945 -0.3048)
			(end -0.67945 0.3048)
			(stroke
				(width 0.1)
				(type default)
			)
			(layer "B.Fab")
		)
		(pad "1" smd circle
			(at 0.40005 0)
			(size 0 0)
			(layers "B.Cu" "B.Mask" "B.Paste")
			(net "P1V2_P1V0_I3C_VDDL1")
		)
		(pad "2" smd circle
			(at -0.40005 0)
			(size 0 0)
			(layers "B.Cu" "B.Mask" "B.Paste")
			(net "GND")
		)
	)
)
